# T6G (Grand Teton) — schematic netlist excerpt (pin names and nets, part order shuffled) for the footprints in the layout excerpt that follows; sources: Cadence DE-HDL packaged netlist, KiCad conversion of 04192023_DAF0TMB3IC0_F0TG_MB_C_brd_V02_OCP.brd

R6261  Q_RES  0 5% CHIP  pkg 0402LF  page 178 : A = USB_HUB2_TI_USB_SSRXP_DN1_MRP_VDD12 ; B = P1V2_CPU0_USB2_DVDD12
R3568  Q_RES  0 5% CHIP  pkg 0402LF  page 237 : A = SMB_INA230_3_3V3AUX_SCL_R ; B = SMB_INA230_3_3V3AUX_SCL_R1

(kicad_pcb
	(version 20260206)
	(generator "pcbnew")
	(generator_version "10.0")
	(general
		(thickness 1.6)
		(legacy_teardrops no)
	)
	(paper "A4")
	(title_block
		(title "04192023_DAF0TMB3IC0_F0TG_MB_C_brd_V02_OCP.brd")
		(comment 1 "Grand Teton / footprints 755-756 of 8354")
	)
	(layers
		(0 "F.Cu" signal "TOP")
		(4 "In1.Cu" signal "GND")
		(6 "In2.Cu" signal "IN1")
		(8 "In3.Cu" signal "GND1")
		(10 "In4.Cu" signal "IN2")
		(12 "In5.Cu" signal "GND2")
		(14 "In6.Cu" signal "IN3")
		(16 "In7.Cu" signal "GND3")
		(18 "In8.Cu" signal "VCC")
		(20 "In9.Cu" signal "VCC1")
		(22 "In10.Cu" signal "GND4")
		(24 "In11.Cu" signal "IN4")
		(26 "In12.Cu" signal "GND5")
		(28 "In13.Cu" signal "IN5")
		(30 "In14.Cu" signal "GND6")
		(32 "In15.Cu" signal "IN6")
		(34 "In16.Cu" signal "GND7")
		(2 "B.Cu" signal "BOTTOM")
		(9 "F.Adhes" user "F.Adhesive")
		(11 "B.Adhes" user "B.Adhesive")
		(13 "F.Paste" user "Package Geometry/Pastemask Top")
		(15 "B.Paste" user "Package Geometry/Pastemask Bottom")
		(5 "F.SilkS" user "Ref Des/Silkscreen Top")
		(7 "B.SilkS" user "Ref Des/Silkscreen Bottom")
		(1 "F.Mask" user "Board Geometry/Soldermask Top")
		(3 "B.Mask" user "Board Geometry/Soldermask Bottom")
		(17 "Dwgs.User" user "User.Drawings")
		(19 "Cmts.User" user "User.Comments")
		(21 "Eco1.User" user "User.Eco1")
		(23 "Eco2.User" user "User.Eco2")
		(25 "Edge.Cuts" user "Board Geometry/Outline")
		(27 "Margin" user)
		(31 "F.CrtYd" user "Package Geometry/Place Bound Top")
		(29 "B.CrtYd" user "Package Geometry/Place Bound Bottom")
		(35 "F.Fab" user "Ref Des/Assembly Top")
		(33 "B.Fab" user "Ref Des/Assembly Bottom")
	)
	(footprint ""
		(layer "F.Cu")
		(at 111.422942 -21.7678 -90)
		(property "Reference" "R6261"
			(at 0 0 270)
			(layer "F.SilkS")
			(hide yes)
			(effects
				(font
					(size 1.27 1.27)
				)
			)
		)
		(property "Value" ""
			(at 0 0 270)
			(layer "F.Fab")
			(effects
				(font
					(size 1.27 1.27)
				)
			)
		)
		(duplicate_pad_numbers_are_jumpers no)
		(fp_line
			(start -0.7874 0.4064)
			(end -0.7874 -0.4064)
			(stroke
				(width 0.1524)
				(type default)
			)
			(layer "F.SilkS")
		)
		(fp_line
			(start 0.7874 0.4064)
			(end -0.7874 0.4064)
			(stroke
				(width 0.1524)
				(type default)
			)
			(layer "F.SilkS")
		)
		(fp_line
			(start -0.7874 -0.4064)
			(end 0.7874 -0.4064)
			(stroke
				(width 0.1524)
				(type default)
			)
			(layer "F.SilkS")
		)
		(fp_line
			(start 0.7874 -0.4064)
			(end 0.7874 0.4064)
			(stroke
				(width 0.1524)
				(type default)
			)
			(layer "F.SilkS")
		)
		(fp_line
			(start -0.67945 0.3048)
			(end -0.67945 -0.305054)
			(stroke
				(width 0.1)
				(type default)
			)
			(layer "F.Fab")
		)
		(fp_line
			(start -0.12065 0.3048)
			(end -0.67945 0.3048)
			(stroke
				(width 0.1)
				(type default)
			)
			(layer "F.Fab")
		)
		(fp_line
			(start 0.120396 0.3048)
			(end 0.120396 0.2794)
			(stroke
				(width 0.1)
				(type default)
			)
			(layer "F.Fab")
		)
		(fp_line
			(start 0.67945 0.3048)
			(end 0.120396 0.3048)
			(stroke
				(width 0.1)
				(type default)
			)
			(layer "F.Fab")
		)
		(fp_line
			(start -0.12065 0.2794)
			(end -0.12065 0.3048)
			(stroke
				(width 0.1)
				(type default)
			)
			(layer "F.Fab")
		)
		(fp_line
			(start 0.120396 0.2794)
			(end -0.12065 0.2794)
			(stroke
				(width 0.1)
				(type default)
			)
			(layer "F.Fab")
		)
		(fp_line
			(start -0.12065 -0.2794)
			(end 0.12065 -0.2794)
			(stroke
				(width 0.1)
				(type default)
			)
			(layer "F.Fab")
		)
		(fp_line
			(start 0.12065 -0.2794)
			(end 0.12065 -0.3048)
			(stroke
				(width 0.1)
				(type default)
			)
			(layer "F.Fab")
		)
		(fp_line
			(start 0.12065 -0.3048)
			(end 0.67945 -0.3048)
			(stroke
				(width 0.1)
				(type default)
			)
			(layer "F.Fab")
		)
		(fp_line
			(start 0.67945 -0.3048)
			(end 0.67945 0.3048)
			(stroke
				(width 0.1)
				(type default)
			)
			(layer "F.Fab")
		)
		(fp_line
			(start -0.67945 -0.305054)
			(end -0.12065 -0.305054)
			(stroke
				(width 0.1)
				(type default)
			)
			(layer "F.Fab")
		)
		(fp_line
			(start -0.12065 -0.305054)
			(end -0.12065 -0.2794)
			(stroke
				(width 0.1)
				(type default)
			)
			(layer "F.Fab")
		)
		(pad "1" smd circle
			(at -0.40005 0 270)
			(size 0 0)
			(layers "F.Cu" "F.Mask" "F.Paste")
			(net "USB_HUB2_TI_USB_SSRXP_DN1_MRP_VDD12")
		)
		(pad "2" smd circle
			(at 0.40005 0 270)
			(size 0 0)
			(layers "F.Cu" "F.Mask" "F.Paste")
			(net "P1V2_CPU0_USB2_DVDD12")
		)
	)
	(footprint ""
		(layer "F.Cu")
		(at 72.4662 -34.788348 180)
		(property "Reference" "R3568"
			(at 0 0 180)
			(layer "F.SilkS")
			(hide yes)
			(effects
				(font
					(size 1.27 1.27)
				)
			)
		)
		(property "Value" ""
			(at 0 0 180)
			(layer "F.Fab")
			(effects
				(font
					(size 1.27 1.27)
				)
			)
		)
		(duplicate_pad_numbers_are_jumpers no)
		(fp_line
			(start 0.7874 0.4064)
			(end -0.7874 0.4064)
			(stroke
				(width 0.1524)
				(type default)
			)
			(layer "F.SilkS")
		)
		(fp_line
			(start 0.7874 -0.4064)
			(end 0.7874 0.4064)
			(stroke
				(width 0.1524)
				(type default)
			)
			(layer "F.SilkS")
		)
		(fp_line
			(start -0.7874 0.4064)
			(end -0.7874 -0.4064)
			(stroke
				(width 0.1524)
				(type default)
			)
			(layer "F.SilkS")
		)
		(fp_line
			(start -0.7874 -0.4064)
			(end 0.7874 -0.4064)
			(stroke
				(width 0.1524)
				(type default)
			)
			(layer "F.SilkS")
		)
		(fp_line
			(start 0.67945 0.3048)
			(end 0.120396 0.3048)
			(stroke
				(width 0.1)
				(type default)
			)
			(layer "F.Fab")
		)
		(fp_line
			(start 0.67945 -0.3048)
			(end 0.67945 0.3048)
			(stroke
				(width 0.1)
				(type default)
			)
			(layer "F.Fab")
		)
		(fp_line
			(start 0.12065 -0.2794)
			(end 0.12065 -0.3048)
			(stroke
				(width 0.1)
				(type default)
			)
			(layer "F.Fab")
		)
		(fp_line
			(start 0.12065 -0.3048)
			(end 0.67945 -0.3048)
			(stroke
				(width 0.1)
				(type default)
			)
			(layer "F.Fab")
		)
		(fp_line
			(start 0.120396 0.3048)
			(end 0.120396 0.2794)
			(stroke
				(width 0.1)
				(type default)
			)
			(layer "F.Fab")
		)
		(fp_line
			(start 0.120396 0.2794)
			(end -0.12065 0.2794)
			(stroke
				(width 0.1)
				(type default)
			)
			(layer "F.Fab")
		)
		(fp_line
			(start -0.12065 0.3048)
			(end -0.67945 0.3048)
			(stroke
				(width 0.1)
				(type default)
			)
			(layer "F.Fab")
		)
		(fp_line
			(start -0.12065 0.2794)
			(end -0.12065 0.3048)
			(stroke
				(width 0.1)
				(type default)
			)
			(layer "F.Fab")
		)
		(fp_line
			(start -0.12065 -0.2794)
			(end 0.12065 -0.2794)
			(stroke
				(width 0.1)
				(type default)
			)
			(layer "F.Fab")
		)
		(fp_line
			(start -0.12065 -0.305054)
			(end -0.12065 -0.2794)
			(stroke
				(width 0.1)
				(type default)
			)
			(layer "F.Fab")
		)
		(fp_line
			(start -0.67945 0.3048)
			(end -0.67945 -0.305054)
			(stroke
				(width 0.1)
				(type default)
			)
			(layer "F.Fab")
		)
		(fp_line
			(start -0.67945 -0.305054)
			(end -0.12065 -0.305054)
			(stroke
				(width 0.1)
				(type default)
			)
			(layer "F.Fab")
		)
		(pad "1" smd circle
			(at -0.40005 0 180)
			(size 0 0)
			(layers "F.Cu" "F.Mask" "F.Paste")
			(net "SMB_INA230_3_3V3AUX_SCL_R")
		)
		(pad "2" smd circle
			(at 0.40005 0 180)
			(size 0 0)
			(layers "F.Cu" "F.Mask" "F.Paste")
			(net "SMB_INA230_3_3V3AUX_SCL_R1")
		)
	)
)
